# BASEBOARD_FAB2 (Tioga Pass) — schematic netlist excerpt (pin names and nets, part order shuffled) for the footprints in the layout excerpt that follows; sources: Cadence DE-HDL packaged netlist, KiCad conversion of Wiwynn_Tioga_Pass_MB.brd

CT54  CAP  1000PF 50V 10% X7R  pkg 0402LF  page 216 : A = A_TSENSE_PVDDQ_ABC ; B = GND
C4W5  CAP  100UF 4V 20% X5R  pkg 0805  page 222 : A = PVTT_DEF ; B = GND
C4B11  CAP  10UF 16V 10% X7R  pkg 0805  page 197 : A = P12V_NVDIMM_DEF ; B = GND

(kicad_pcb
	(version 20260206)
	(generator "pcbnew")
	(generator_version "10.0")
	(general
		(thickness 1.6)
		(legacy_teardrops no)
	)
	(paper "A4")
	(title_block
		(title "Wiwynn_Tioga_Pass_MB.brd")
		(comment 1 "Tioga Pass / footprints 1683-1685 of 4770")
	)
	(layers
		(0 "F.Cu" signal "TOP")
		(4 "In1.Cu" signal "L2GND")
		(6 "In2.Cu" signal "L3")
		(8 "In3.Cu" signal "L4GND")
		(10 "In4.Cu" signal "L5")
		(12 "In5.Cu" signal "L6GND")
		(14 "In6.Cu" signal "L7VCC")
		(16 "In7.Cu" signal "L8VCC")
		(18 "In8.Cu" signal "L9GND")
		(20 "In9.Cu" signal "L10")
		(22 "In10.Cu" signal "L11GND")
		(24 "In11.Cu" signal "L12")
		(26 "In12.Cu" signal "L13GND")
		(2 "B.Cu" signal "BOTTOM")
		(9 "F.Adhes" user "F.Adhesive")
		(11 "B.Adhes" user "B.Adhesive")
		(13 "F.Paste" user "Package Geometry/Pastemask Top")
		(15 "B.Paste" user "Package Geometry/Pastemask Bottom")
		(5 "F.SilkS" user "Ref Des/Silkscreen Top")
		(7 "B.SilkS" user "Ref Des/Silkscreen Bottom")
		(1 "F.Mask" user "Board Geometry/Soldermask Top")
		(3 "B.Mask" user "Board Geometry/Soldermask Bottom")
		(17 "Dwgs.User" user "User.Drawings")
		(19 "Cmts.User" user "User.Comments")
		(21 "Eco1.User" user "User.Eco1")
		(23 "Eco2.User" user "User.Eco2")
		(25 "Edge.Cuts" user "Board Geometry/Outline")
		(27 "Margin" user)
		(31 "F.CrtYd" user "Package Geometry/Place Bound Top")
		(29 "B.CrtYd" user "Package Geometry/Place Bound Bottom")
		(35 "F.Fab" user "Ref Des/Assembly Top")
		(33 "B.Fab" user "Ref Des/Assembly Bottom")
	)
	(footprint ""
		(layer "F.Cu")
		(at 193.04 -130.048 -90)
		(property "Reference" "C4B11"
			(at 0 0 270)
			(layer "F.SilkS")
			(hide yes)
			(effects
				(font
					(size 1.27 1.27)
				)
			)
		)
		(property "Value" ""
			(at 0 0 270)
			(layer "F.Fab")
			(effects
				(font
					(size 1.27 1.27)
				)
			)
		)
		(duplicate_pad_numbers_are_jumpers no)
		(fp_rect
			(start -0.7239 1.9939)
			(end 0.7239 -0.2159)
			(stroke
				(width 0)
				(type default)
			)
			(fill no)
			(layer "F.CrtYd")
		)
		(fp_line
			(start -0.7239 1.9939)
			(end 0.7239 1.9939)
			(stroke
				(width 0.1)
				(type default)
			)
			(layer "F.Fab")
		)
		(fp_line
			(start 0.7239 1.9939)
			(end 0.7239 -0.2159)
			(stroke
				(width 0.1)
				(type default)
			)
			(layer "F.Fab")
		)
		(fp_line
			(start -0.7239 -0.2159)
			(end -0.7239 1.9939)
			(stroke
				(width 0.1)
				(type default)
			)
			(layer "F.Fab")
		)
		(fp_line
			(start 0.7239 -0.2159)
			(end -0.7239 -0.2159)
			(stroke
				(width 0.1)
				(type default)
			)
			(layer "F.Fab")
		)
		(pad "1" smd rect
			(at 0 0 270)
			(size 1.27 1.016)
			(layers "F.Cu" "F.Mask" "F.Paste")
			(net "P12V_NVDIMM_DEF")
		)
		(pad "2" smd rect
			(at 0 1.778 270)
			(size 1.27 1.016)
			(layers "F.Cu" "F.Mask" "F.Paste")
			(net "GND")
		)
		(zone
			(layer "F.Cu")
			(hatch none 0.5)
			(connect_pads
				(clearance 0)
			)
			(min_thickness 0.25)
			(keepout
				(tracks not_allowed)
				(vias allowed)
				(pads allowed)
				(copperpour not_allowed)
				(footprints allowed)
			)
			(placement
				(enabled no)
				(sheetname "")
			)
			(fill
				(thermal_gap 0.5)
				(thermal_bridge_width 0.5)
				(island_removal_mode 0)
			)
			(polygon
				(pts
					(xy 191.77 -130.683) (xy 191.77 -129.413) (xy 192.532 -129.413) (xy 192.532 -130.683)
				)
			)
		)
	)
	(footprint ""
		(layer "F.Cu")
		(at 351.630234 -0.12192)
		(property "Reference" "CT54"
			(at -5.15747 -5.207 270)
			(unlocked yes)
			(layer "F.SilkS")
			(effects
				(font
					(size 0.7874 0.5842)
					(thickness 0.1524)
				)
				(justify left)
			)
		)
		(property "Value" ""
			(at 0 0 0)
			(layer "F.Fab")
			(effects
				(font
					(size 1.27 1.27)
				)
			)
		)
		(duplicate_pad_numbers_are_jumpers no)
		(fp_poly
			(pts
				(xy 0.3048 -0.1016) (xy 0.3048 0.9906) (xy -0.3048 0.9906) (xy -0.3048 -0.1016)
			)
			(stroke
				(width 0)
				(type default)
			)
			(fill no)
			(layer "F.CrtYd")
		)
		(fp_line
			(start -0.3048 -0.1016)
			(end -0.3048 0.9906)
			(stroke
				(width 0.1)
				(type default)
			)
			(layer "F.Fab")
		)
		(fp_line
			(start -0.3048 0.9906)
			(end 0.3048 0.9906)
			(stroke
				(width 0.1)
				(type default)
			)
			(layer "F.Fab")
		)
		(fp_line
			(start 0.3048 -0.1016)
			(end -0.3048 -0.1016)
			(stroke
				(width 0.1)
				(type default)
			)
			(layer "F.Fab")
		)
		(fp_line
			(start 0.3048 0.9906)
			(end 0.3048 -0.1016)
			(stroke
				(width 0.1)
				(type default)
			)
			(layer "F.Fab")
		)
		(pad "1" smd rect
			(at 0 0)
			(size 0.508 0.508)
			(layers "F.Cu" "F.Mask" "F.Paste")
			(net "A_TSENSE_PVDDQ_ABC")
		)
		(pad "2" smd rect
			(at 0 0.889)
			(size 0.508 0.508)
			(layers "F.Cu" "F.Mask" "F.Paste")
			(net "GND")
		)
		(zone
			(layer "F.Cu")
			(hatch none 0.5)
			(connect_pads
				(clearance 0)
			)
			(min_thickness 0.25)
			(keepout
				(tracks allowed)
				(vias not_allowed)
				(pads allowed)
				(copperpour not_allowed)
				(footprints allowed)
			)
			(placement
				(enabled no)
				(sheetname "")
			)
			(fill
				(thermal_gap 0.5)
				(thermal_bridge_width 0.5)
				(island_removal_mode 0)
			)
			(polygon
				(pts
					(xy 351.376234 0.13208) (xy 351.884234 0.13208) (xy 351.884234 0.51308) (xy 351.376234 0.51308)
				)
			)
		)
		(zone
			(layer "F.Cu")
			(hatch none 0.5)
			(connect_pads
				(clearance 0)
			)
			(min_thickness 0.25)
			(keepout
				(tracks not_allowed)
				(vias allowed)
				(pads allowed)
				(copperpour not_allowed)
				(footprints allowed)
			)
			(placement
				(enabled no)
				(sheetname "")
			)
			(fill
				(thermal_gap 0.5)
				(thermal_bridge_width 0.5)
				(island_removal_mode 0)
			)
			(polygon
				(pts
					(xy 351.376234 0.51308) (xy 351.884234 0.51308) (xy 351.884234 0.13208) (xy 351.376234 0.13208)
				)
			)
		)
	)
	(footprint ""
		(layer "F.Cu")
		(at 181.70398 -155.83662 90)
		(property "Reference" "C4W5"
			(at 1.47828 0.78994 0)
			(unlocked yes)
			(layer "F.SilkS")
			(effects
				(font
					(size 0.4064 0.254)
					(thickness 0.1524)
				)
			)
		)
		(property "Value" ""
			(at 0 0 90)
			(layer "F.Fab")
			(effects
				(font
					(size 1.27 1.27)
				)
			)
		)
		(duplicate_pad_numbers_are_jumpers no)
		(fp_poly
			(pts
				(xy -0.7239 -0.2159) (xy 0.7239 -0.2159) (xy 0.7239 1.9939) (xy -0.7239 1.9939)
			)
			(stroke
				(width 0)
				(type default)
			)
			(fill no)
			(layer "F.CrtYd")
		)
		(fp_line
			(start 0.7239 -0.2159)
			(end -0.7239 -0.2159)
			(stroke
				(width 0.1)
				(type default)
			)
			(layer "F.Fab")
		)
		(fp_line
			(start -0.7239 -0.2159)
			(end -0.7239 1.9939)
			(stroke
				(width 0.1)
				(type default)
			)
			(layer "F.Fab")
		)
		(fp_line
			(start 0.7239 1.9939)
			(end 0.7239 -0.2159)
			(stroke
				(width 0.1)
				(type default)
			)
			(layer "F.Fab")
		)
		(fp_line
			(start -0.7239 1.9939)
			(end 0.7239 1.9939)
			(stroke
				(width 0.1)
				(type default)
			)
			(layer "F.Fab")
		)
		(pad "1" smd rect
			(at 0 0 90)
			(size 1.27 1.016)
			(layers "F.Cu" "F.Mask" "F.Paste")
			(net "PVTT_DEF")
		)
		(pad "2" smd rect
			(at 0 1.778 90)
			(size 1.27 1.016)
			(layers "F.Cu" "F.Mask" "F.Paste")
			(net "GND")
		)
		(zone
			(layer "F.Cu")
			(hatch none 0.5)
			(connect_pads
				(clearance 0)
			)
			(min_thickness 0.25)
			(keepout
				(tracks not_allowed)
				(vias allowed)
				(pads allowed)
				(copperpour not_allowed)
				(footprints allowed)
			)
			(placement
				(enabled no)
				(sheetname "")
			)
			(fill
				(thermal_gap 0.5)
				(thermal_bridge_width 0.5)
				(island_removal_mode 0)
			)
			(polygon
				(pts
					(xy 182.21198 -155.20162) (xy 182.21198 -156.47162) (xy 182.97398 -156.47162) (xy 182.97398 -155.20162)
				)
			)
		)
	)
)
